(kicad_pcb
	(version 20241229)
	(generator "pcbnew")
	(generator_version "9.0")
	(general
		(thickness 1.61)
		(legacy_teardrops no)
	)
	(paper "A3")
	(title_block
		(title "SO-DIMM DDR5 Tester")
		(date "2025-11-26")
		(rev "1.3.0")
		(comment 9 "footprints 418-423 of 627")
	)
	(layers
		(0 "F.Cu" signal)
		(4 "In1.Cu" power)
		(6 "In2.Cu" mixed)
		(8 "In3.Cu" power)
		(10 "In4.Cu" mixed)
		(12 "In5.Cu" power)
		(14 "In6.Cu" mixed)
		(16 "In7.Cu" power)
		(18 "In8.Cu" power)
		(20 "In9.Cu" mixed)
		(22 "In10.Cu" power)
		(2 "B.Cu" signal)
		(9 "F.Adhes" user "F.Adhesive")
		(11 "B.Adhes" user "B.Adhesive")
		(13 "F.Paste" user)
		(15 "B.Paste" user)
		(5 "F.SilkS" user "F.Silkscreen")
		(7 "B.SilkS" user "B.Silkscreen")
		(1 "F.Mask" user)
		(3 "B.Mask" user)
		(17 "Dwgs.User" user "User.Drawings")
		(19 "Cmts.User" user "User.Comments")
		(21 "Eco1.User" user "User.Eco1")
		(23 "Eco2.User" user "User.Eco2")
		(25 "Edge.Cuts" user)
		(27 "Margin" user)
		(31 "F.CrtYd" user "F.Courtyard")
		(29 "B.CrtYd" user "B.Courtyard")
		(35 "F.Fab" user)
		(33 "B.Fab" user)
	)
	(footprint "antmicro-footprints:R_0402_1005Metric"
		(layer "B.Cu")
		(at 202.881001 170.222 90)
		(descr "Resistor SMD 0402")
		(tags "resistor SMD 0402")
		(property "Reference" "R169"
			(at -1.122484 0.368999 270)
			(layer "B.SilkS")
			(effects
				(font
					(size 0.7 0.7)
					(thickness 0.15)
				)
				(justify left bottom mirror)
			)
		)
		(property "Value" "R_0R_0402"
			(at -1.011843 -1.772047 270)
			(layer "B.Fab")
			(effects
				(font
					(size 0.7 0.7)
					(thickness 0.15)
				)
				(justify left bottom mirror)
			)
		)
		(property "Datasheet" "https://industrial.panasonic.com/cdbs/www-data/pdf/RDA0000/AOA0000C301.pdf"
			(at 0 0 90)
			(layer "F.Fab")
			(hide yes)
			(effects
				(font
					(size 1.27 1.27)
					(thickness 0.15)
				)
			)
		)
		(property "Author" "Antmicro"
			(at 373.103001 -32.659001 0)
			(layer "B.Fab")
			(hide yes)
			(effects
				(font
					(size 1 1)
					(thickness 0.15)
				)
				(justify mirror)
			)
		)
		(property "Current" "1A"
			(at 373.103001 -32.659001 0)
			(layer "B.Fab")
			(hide yes)
			(effects
				(font
					(size 1 1)
					(thickness 0.15)
				)
				(justify mirror)
			)
		)
		(property "License" "Apache-2.0"
			(at 373.103001 -32.659001 0)
			(layer "B.Fab")
			(hide yes)
			(effects
				(font
					(size 1 1)
					(thickness 0.15)
				)
				(justify mirror)
			)
		)
		(property "MPN" "ERJ2GE0R00X"
			(at 373.103001 -32.659001 0)
			(layer "B.Fab")
			(hide yes)
			(effects
				(font
					(size 1 1)
					(thickness 0.15)
				)
				(justify mirror)
			)
		)
		(property "Manufacturer" "Panasonic"
			(at 373.103001 -32.659001 0)
			(layer "B.Fab")
			(hide yes)
			(effects
				(font
					(size 1 1)
					(thickness 0.15)
				)
				(justify mirror)
			)
		)
		(property "Tolerance" ""
			(at 373.103001 -32.659001 0)
			(layer "B.Fab")
			(hide yes)
			(effects
				(font
					(size 1 1)
					(thickness 0.15)
				)
				(justify mirror)
			)
		)
		(property "Val" "0R"
			(at 373.103001 -32.659001 0)
			(layer "B.Fab")
			(hide yes)
			(effects
				(font
					(size 1 1)
					(thickness 0.15)
				)
				(justify mirror)
			)
		)
		(sheetname "/Supply/")
		(sheetfile "supply.kicad_sch")
		(attr exclude_from_pos_files exclude_from_bom dnp)
		(fp_rect
			(start -0.93 0.47)
			(end 0.93 -0.47)
			(stroke
				(width 0.05)
				(type solid)
			)
			(fill no)
			(layer "B.CrtYd")
		)
		(fp_rect
			(start -0.5 0.25)
			(end 0.5 -0.25)
			(stroke
				(width 0.15)
				(type solid)
			)
			(fill no)
			(layer "B.Fab")
		)
		(pad "1" smd roundrect
			(at -0.485 0 90)
			(size 0.59 0.64)
			(layers "B.Cu" "B.Mask" "B.Paste")
			(roundrect_rratio 0.25)
			(net 1 "GND")
			(pintype "passive")
		)
		(pad "2" smd roundrect
			(at 0.485 0 90)
			(size 0.59 0.64)
			(layers "B.Cu" "B.Mask" "B.Paste")
			(roundrect_rratio 0.25)
			(net 218 "/Supply/FB8")
			(pintype "passive")
		)
	)
	(footprint "antmicro-footprints:C_0402_1005Metric"
		(layer "B.Cu")
		(at 172.800501 196.376)
		(descr "Capacitor SMD 0402")
		(tags "capacitor SMD 0402")
		(property "Reference" "C204"
			(at 0 0.699 180)
			(layer "B.SilkS")
			(hide yes)
			(effects
				(font
					(size 0.7 0.7)
					(thickness 0.15)
				)
				(justify left bottom mirror)
			)
		)
		(property "Value" "C_100n_0402"
			(at -1.022927 -2.155213 180)
			(layer "B.Fab")
			(effects
				(font
					(size 0.7 0.7)
					(thickness 0.15)
				)
				(justify left bottom mirror)
			)
		)
		(property "Datasheet" "https://www.murata.com/products/productdetail?partno=GRM155R61H104KE14%23"
			(at 0 0 0)
			(layer "F.Fab")
			(hide yes)
			(effects
				(font
					(size 1.27 1.27)
					(thickness 0.15)
				)
			)
		)
		(property "Author" "Antmicro"
			(at 0 0 0)
			(layer "B.Fab")
			(hide yes)
			(effects
				(font
					(size 1 1)
					(thickness 0.15)
				)
				(justify mirror)
			)
		)
		(property "Dielectric" "X5R"
			(at 0 0 0)
			(layer "B.Fab")
			(hide yes)
			(effects
				(font
					(size 1 1)
					(thickness 0.15)
				)
				(justify mirror)
			)
		)
		(property "License" "Apache-2.0"
			(at 0 0 0)
			(layer "B.Fab")
			(hide yes)
			(effects
				(font
					(size 1 1)
					(thickness 0.15)
				)
				(justify mirror)
			)
		)
		(property "MPN" "GRM155R61H104KE14D"
			(at 0 0 0)
			(layer "B.Fab")
			(hide yes)
			(effects
				(font
					(size 1 1)
					(thickness 0.15)
				)
				(justify mirror)
			)
		)
		(property "Manufacturer" "Murata"
			(at 0 0 0)
			(layer "B.Fab")
			(hide yes)
			(effects
				(font
					(size 1 1)
					(thickness 0.15)
				)
				(justify mirror)
			)
		)
		(property "Val" "100n"
			(at 0 0 0)
			(layer "B.Fab")
			(hide yes)
			(effects
				(font
					(size 1 1)
					(thickness 0.15)
				)
				(justify mirror)
			)
		)
		(property "Voltage" "50V"
			(at 0 0 0)
			(layer "B.Fab")
			(hide yes)
			(effects
				(font
					(size 1 1)
					(thickness 0.15)
				)
				(justify mirror)
			)
		)
		(sheetname "/Supply/")
		(sheetfile "supply.kicad_sch")
		(attr smd)
		(fp_rect
			(start -0.9659 0.481258)
			(end 0.9649 -0.458742)
			(stroke
				(width 0.05)
				(type solid)
			)
			(fill no)
			(layer "B.CrtYd")
		)
		(fp_line
			(start -0.499 -0.248)
			(end -0.499 0.25)
			(stroke
				(width 0.15)
				(type solid)
			)
			(layer "B.Fab")
		)
		(fp_line
			(start -0.499 0.25)
			(end 0.499 0.25)
			(stroke
				(width 0.15)
				(type solid)
			)
			(layer "B.Fab")
		)
		(fp_line
			(start 0.499 -0.248)
			(end -0.499 -0.248)
			(stroke
				(width 0.15)
				(type solid)
			)
			(layer "B.Fab")
		)
		(fp_line
			(start 0.499 0.25)
			(end 0.499 -0.248)
			(stroke
				(width 0.15)
				(type solid)
			)
			(layer "B.Fab")
		)
		(pad "1" smd roundrect
			(at -0.484 0)
			(size 0.59 0.64)
			(layers "B.Cu" "B.Mask" "B.Paste")
			(roundrect_rratio 0.25)
			(net 1 "GND")
			(pintype "passive")
		)
		(pad "2" smd roundrect
			(at 0.484 0)
			(size 0.59 0.64)
			(layers "B.Cu" "B.Mask" "B.Paste")
			(roundrect_rratio 0.25)
			(net 38 "VDC")
			(pintype "passive")
		)
	)
	(footprint "antmicro-footprints:R_0402_1005Metric"
		(layer "B.Cu")
		(at 141.67 142.4 -90)
		(descr "Resistor SMD 0402")
		(tags "resistor SMD 0402")
		(property "Reference" "R30"
			(at -3.044968 -0.354606 90)
			(layer "B.SilkS")
			(effects
				(font
					(size 0.7 0.7)
					(thickness 0.15)
				)
				(justify left bottom mirror)
			)
		)
		(property "Value" "R_0R_0402"
			(at -1.011843 -1.772047 90)
			(layer "B.Fab")
			(effects
				(font
					(size 0.7 0.7)
					(thickness 0.15)
				)
				(justify left bottom mirror)
			)
		)
		(property "Datasheet" "https://industrial.panasonic.com/cdbs/www-data/pdf/RDA0000/AOA0000C301.pdf"
			(at 0 0 270)
			(layer "F.Fab")
			(hide yes)
			(effects
				(font
					(size 1.27 1.27)
					(thickness 0.15)
				)
			)
		)
		(property "Author" "Antmicro"
			(at -0.73 284.07 0)
			(layer "B.Fab")
			(hide yes)
			(effects
				(font
					(size 1 1)
					(thickness 0.15)
				)
				(justify mirror)
			)
		)
		(property "Current" "1A"
			(at -0.73 284.07 0)
			(layer "B.Fab")
			(hide yes)
			(effects
				(font
					(size 1 1)
					(thickness 0.15)
				)
				(justify mirror)
			)
		)
		(property "License" "Apache-2.0"
			(at -0.73 284.07 0)
			(layer "B.Fab")
			(hide yes)
			(effects
				(font
					(size 1 1)
					(thickness 0.15)
				)
				(justify mirror)
			)
		)
		(property "MPN" "ERJ2GE0R00X"
			(at -0.73 284.07 0)
			(layer "B.Fab")
			(hide yes)
			(effects
				(font
					(size 1 1)
					(thickness 0.15)
				)
				(justify mirror)
			)
		)
		(property "Manufacturer" "Panasonic"
			(at -0.73 284.07 0)
			(layer "B.Fab")
			(hide yes)
			(effects
				(font
					(size 1 1)
					(thickness 0.15)
				)
				(justify mirror)
			)
		)
		(property "Tolerance" ""
			(at -0.73 284.07 0)
			(layer "B.Fab")
			(hide yes)
			(effects
				(font
					(size 1 1)
					(thickness 0.15)
				)
				(justify mirror)
			)
		)
		(property "Val" "0R"
			(at -0.73 284.07 0)
			(layer "B.Fab")
			(hide yes)
			(effects
				(font
					(size 1 1)
					(thickness 0.15)
				)
				(justify mirror)
			)
		)
		(sheetname "/DDR5 SODIMM/")
		(sheetfile "ddr5-sodimm.kicad_sch")
		(attr exclude_from_pos_files exclude_from_bom dnp)
		(fp_rect
			(start -0.93 0.47)
			(end 0.93 -0.47)
			(stroke
				(width 0.05)
				(type solid)
			)
			(fill no)
			(layer "B.CrtYd")
		)
		(fp_rect
			(start -0.5 0.25)
			(end 0.5 -0.25)
			(stroke
				(width 0.15)
				(type solid)
			)
			(fill no)
			(layer "B.Fab")
		)
		(pad "1" smd roundrect
			(at -0.485 0 270)
			(size 0.59 0.64)
			(layers "B.Cu" "B.Mask" "B.Paste")
			(roundrect_rratio 0.25)
			(net 1 "GND")
			(pintype "passive")
		)
		(pad "2" smd roundrect
			(at 0.485 0 270)
			(size 0.59 0.64)
			(layers "B.Cu" "B.Mask" "B.Paste")
			(roundrect_rratio 0.25)
			(net 171 "/DDR5 SODIMM/RFU2")
			(pintype "passive")
		)
	)
	(footprint "antmicro-footprints:C_0402_1005Metric"
		(layer "B.Cu")
		(at 141.375501 177.801 90)
		(descr "Capacitor SMD 0402 (1005 Metric), square (rectangular) end terminal, IPC_7351 nominal, (Body size source: IPC-SM-782 page 76, https://www.pcb-3d.com/wordpress/wp-content/uploads/ipc-sm-782a_amendment_1_and_2.pdf)")
		(tags "capacitor 0402")
		(property "Reference" "C50"
			(at 0 1.17 270)
			(layer "B.SilkS")
			(hide yes)
			(effects
				(font
					(size 0.7 0.7)
					(thickness 0.15)
				)
				(justify left bottom mirror)
			)
		)
		(property "Value" "C_4u7_0402"
			(at 0 -1.169 270)
			(layer "B.Fab")
			(effects
				(font
					(size 0.7 0.7)
					(thickness 0.15)
				)
				(justify left bottom mirror)
			)
		)
		(property "Datasheet" "https://www.murata.com/products/productdetail?partno=GRM155R61A475MEAA%23"
			(at 0 0 90)
			(layer "F.Fab")
			(hide yes)
			(effects
				(font
					(size 1.27 1.27)
					(thickness 0.15)
				)
			)
		)
		(property "Author" "Antmicro"
			(at 319.176501 36.425499 0)
			(layer "B.Fab")
			(hide yes)
			(effects
				(font
					(size 1 1)
					(thickness 0.15)
				)
				(justify mirror)
			)
		)
		(property "Dielectric" ""
			(at 319.176501 36.425499 0)
			(layer "B.Fab")
			(hide yes)
			(effects
				(font
					(size 1 1)
					(thickness 0.15)
				)
				(justify mirror)
			)
		)
		(property "License" "Apache-2.0"
			(at 319.176501 36.425499 0)
			(layer "B.Fab")
			(hide yes)
			(effects
				(font
					(size 1 1)
					(thickness 0.15)
				)
				(justify mirror)
			)
		)
		(property "MPN" "GRM155R61A475MEAAD"
			(at 319.176501 36.425499 0)
			(layer "B.Fab")
			(hide yes)
			(effects
				(font
					(size 1 1)
					(thickness 0.15)
				)
				(justify mirror)
			)
		)
		(property "Manufacturer" "Murata"
			(at 319.176501 36.425499 0)
			(layer "B.Fab")
			(hide yes)
			(effects
				(font
					(size 1 1)
					(thickness 0.15)
				)
				(justify mirror)
			)
		)
		(property "Val" "4u7"
			(at 319.176501 36.425499 0)
			(layer "B.Fab")
			(hide yes)
			(effects
				(font
					(size 1 1)
					(thickness 0.15)
				)
				(justify mirror)
			)
		)
		(property "Voltage" ""
			(at 319.176501 36.425499 0)
			(layer "B.Fab")
			(hide yes)
			(effects
				(font
					(size 1 1)
					(thickness 0.15)
				)
				(justify mirror)
			)
		)
		(sheetname "/FPGA power/")
		(sheetfile "fpga-power.kicad_sch")
		(attr smd)
		(fp_rect
			(start -0.9656 0.4572)
			(end 0.9652 -0.4828)
			(stroke
				(width 0.05)
				(type solid)
			)
			(fill no)
			(layer "B.CrtYd")
		)
		(fp_line
			(start 0.498 -0.248)
			(end -0.5 -0.248)
			(stroke
				(width 0.15)
				(type solid)
			)
			(layer "B.Fab")
		)
		(fp_line
			(start -0.5 -0.248)
			(end -0.5 0.25)
			(stroke
				(width 0.15)
				(type solid)
			)
			(layer "B.Fab")
		)
		(fp_line
			(start 0.498 0.25)
			(end 0.498 -0.248)
			(stroke
				(width 0.15)
				(type solid)
			)
			(layer "B.Fab")
		)
		(fp_line
			(start -0.5 0.25)
			(end 0.498 0.25)
			(stroke
				(width 0.15)
				(type solid)
			)
			(layer "B.Fab")
		)
		(pad "1" smd roundrect
			(at -0.5 0)
			(size 0.6 0.6)
			(layers "B.Cu" "B.Mask" "B.Paste")
			(roundrect_rratio 0.25)
			(net 188 "+1V8")
			(pintype "passive")
		)
		(pad "2" smd roundrect
			(at 0.498 0 90)
			(size 0.6 0.6)
			(layers "B.Cu" "B.Mask" "B.Paste")
			(roundrect_rratio 0.25)
			(net 1 "GND")
			(pintype "passive")
		)
	)
	(footprint "antmicro-footprints:R_0402_1005Metric"
		(layer "B.Cu")
		(at 125.877001 173.3005)
		(descr "Resistor SMD 0402 (1005 Metric), square (rectangular) end terminal, IPC_7351 nominal, (Body size source: IPC-SM-782 page 76, https://www.pcb-3d.com/wordpress/wp-content/uploads/ipc-sm-782a_amendment_1_and_2.pdf)")
		(tags "resistor 0402")
		(property "Reference" "R96"
			(at 0 1.17 180)
			(layer "B.SilkS")
			(hide yes)
			(effects
				(font
					(size 0.7 0.7)
					(thickness 0.15)
				)
				(justify left bottom mirror)
			)
		)
		(property "Value" "R_0R_0402"
			(at 0 -1.169 180)
			(layer "B.Fab")
			(effects
				(font
					(size 0.7 0.7)
					(thickness 0.15)
				)
				(justify left bottom mirror)
			)
		)
		(property "Datasheet" "https://industrial.panasonic.com/cdbs/www-data/pdf/RDA0000/AOA0000C301.pdf"
			(at 0 0 0)
			(layer "F.Fab")
			(hide yes)
			(effects
				(font
					(size 1.27 1.27)
					(thickness 0.15)
				)
			)
		)
		(property "Author" "Antmicro"
			(at 0 0 0)
			(layer "B.Fab")
			(hide yes)
			(effects
				(font
					(size 1 1)
					(thickness 0.15)
				)
				(justify mirror)
			)
		)
		(property "Current" "1A"
			(at 0 0 0)
			(layer "B.Fab")
			(hide yes)
			(effects
				(font
					(size 1 1)
					(thickness 0.15)
				)
				(justify mirror)
			)
		)
		(property "License" "Apache-2.0"
			(at 0 0 0)
			(layer "B.Fab")
			(hide yes)
			(effects
				(font
					(size 1 1)
					(thickness 0.15)
				)
				(justify mirror)
			)
		)
		(property "MPN" "ERJ2GE0R00X"
			(at 0 0 0)
			(layer "B.Fab")
			(hide yes)
			(effects
				(font
					(size 1 1)
					(thickness 0.15)
				)
				(justify mirror)
			)
		)
		(property "Manufacturer" "Panasonic"
			(at 0 0 0)
			(layer "B.Fab")
			(hide yes)
			(effects
				(font
					(size 1 1)
					(thickness 0.15)
				)
				(justify mirror)
			)
		)
		(property "Tolerance" ""
			(at 0 0 0)
			(layer "B.Fab")
			(hide yes)
			(effects
				(font
					(size 1 1)
					(thickness 0.15)
				)
				(justify mirror)
			)
		)
		(property "Val" "0R"
			(at 0 0 0)
			(layer "B.Fab")
			(hide yes)
			(effects
				(font
					(size 1 1)
					(thickness 0.15)
				)
				(justify mirror)
			)
		)
		(sheetname "/FPGA banks unused/")
		(sheetfile "fpga-bank-13-15.kicad_sch")
		(attr smd)
		(fp_line
			(start -0.95 -0.45)
			(end -0.95 0.46)
			(stroke
				(width 0.05)
				(type solid)
			)
			(layer "B.CrtYd")
		)
		(fp_line
			(start -0.95 0.46)
			(end 0.9652 0.46)
			(stroke
				(width 0.05)
				(type solid)
			)
			(layer "B.CrtYd")
		)
		(fp_line
			(start 0.9652 -0.45)
			(end -0.95 -0.45)
			(stroke
				(width 0.05)
				(type solid)
			)
			(layer "B.CrtYd")
		)
		(fp_line
			(start 0.9652 0.46)
			(end 0.9652 -0.45)
			(stroke
				(width 0.05)
				(type solid)
			)
			(layer "B.CrtYd")
		)
		(fp_line
			(start -0.5 -0.249)
			(end -0.5 0.25)
			(stroke
				(width 0.15)
				(type solid)
			)
			(layer "B.Fab")
		)
		(fp_line
			(start -0.5 0.25)
			(end 0.499 0.25)
			(stroke
				(width 0.15)
				(type solid)
			)
			(layer "B.Fab")
		)
		(fp_line
			(start 0.499 -0.249)
			(end -0.5 -0.249)
			(stroke
				(width 0.15)
				(type solid)
			)
			(layer "B.Fab")
		)
		(fp_line
			(start 0.499 0.25)
			(end 0.499 -0.249)
			(stroke
				(width 0.15)
				(type solid)
			)
			(layer "B.Fab")
		)
		(pad "1" smd roundrect
			(at -0.5 0 270)
			(size 0.6 0.6)
			(layers "B.Cu" "B.Mask" "B.Paste")
			(roundrect_rratio 0.25)
			(net 200 "+3V3")
			(pintype "passive")
		)
		(pad "2" smd roundrect
			(at 0.499 0)
			(size 0.6 0.6)
			(layers "B.Cu" "B.Mask" "B.Paste")
			(roundrect_rratio 0.25)
			(net 376 "Net-(R96-Pad2)")
			(pintype "passive")
		)
	)
	(footprint "antmicro-footprints:C_0402_1005Metric"
		(layer "B.Cu")
		(at 147.875501 176.301 180)
		(descr "Capacitor SMD 0402 (1005 Metric), square (rectangular) end terminal, IPC_7351 nominal, (Body size source: IPC-SM-782 page 76, https://www.pcb-3d.com/wordpress/wp-content/uploads/ipc-sm-782a_amendment_1_and_2.pdf)")
		(tags "capacitor 0402")
		(property "Reference" "C96"
			(at 0 1.17 0)
			(layer "B.SilkS")
			(hide yes)
			(effects
				(font
					(size 0.7 0.7)
					(thickness 0.15)
				)
				(justify left bottom mirror)
			)
		)
		(property "Value" "C_100n_0402"
			(at 0 -1.169 0)
			(layer "B.Fab")
			(effects
				(font
					(size 0.7 0.7)
					(thickness 0.15)
				)
				(justify left bottom mirror)
			)
		)
		(property "Datasheet" "https://www.murata.com/products/productdetail?partno=GRM155R61H104KE14%23"
			(at 0 0 180)
			(layer "F.Fab")
			(hide yes)
			(effects
				(font
					(size 1.27 1.27)
					(thickness 0.15)
				)
			)
		)
		(property "Author" "Antmicro"
			(at 295.751002 352.602 0)
			(layer "B.Fab")
			(hide yes)
			(effects
				(font
					(size 1 1)
					(thickness 0.15)
				)
				(justify mirror)
			)
		)
		(property "Dielectric" "X5R"
			(at 295.751002 352.602 0)
			(layer "B.Fab")
			(hide yes)
			(effects
				(font
					(size 1 1)
					(thickness 0.15)
				)
				(justify mirror)
			)
		)
		(property "License" "Apache-2.0"
			(at 295.751002 352.602 0)
			(layer "B.Fab")
			(hide yes)
			(effects
				(font
					(size 1 1)
					(thickness 0.15)
				)
				(justify mirror)
			)
		)
		(property "MPN" "GRM155R61H104KE14D"
			(at 295.751002 352.602 0)
			(layer "B.Fab")
			(hide yes)
			(effects
				(font
					(size 1 1)
					(thickness 0.15)
				)
				(justify mirror)
			)
		)
		(property "Manufacturer" "Murata"
			(at 295.751002 352.602 0)
			(layer "B.Fab")
			(hide yes)
			(effects
				(font
					(size 1 1)
					(thickness 0.15)
				)
				(justify mirror)
			)
		)
		(property "Val" "100n"
			(at 295.751002 352.602 0)
			(layer "B.Fab")
			(hide yes)
			(effects
				(font
					(size 1 1)
					(thickness 0.15)
				)
				(justify mirror)
			)
		)
		(property "Voltage" "50V"
			(at 295.751002 352.602 0)
			(layer "B.Fab")
			(hide yes)
			(effects
				(font
					(size 1 1)
					(thickness 0.15)
				)
				(justify mirror)
			)
		)
		(sheetname "/FPGA power/")
		(sheetfile "fpga-power.kicad_sch")
		(attr smd)
		(fp_rect
			(start -0.9656 0.4572)
			(end 0.9652 -0.4828)
			(stroke
				(width 0.05)
				(type solid)
			)
			(fill no)
			(layer "B.CrtYd")
		)
		(fp_line
			(start 0.498 0.25)
			(end 0.498 -0.248)
			(stroke
				(width 0.15)
				(type solid)
			)
			(layer "B.Fab")
		)
		(fp_line
			(start 0.498 -0.248)
			(end -0.5 -0.248)
			(stroke
				(width 0.15)
				(type solid)
			)
			(layer "B.Fab")
		)
		(fp_line
			(start -0.5 0.25)
			(end 0.498 0.25)
			(stroke
				(width 0.15)
				(type solid)
			)
			(layer "B.Fab")
		)
		(fp_line
			(start -0.5 -0.248)
			(end -0.5 0.25)
			(stroke
				(width 0.15)
				(type solid)
			)
			(layer "B.Fab")
		)
		(pad "1" smd roundrect
			(at -0.5 0 90)
			(size 0.6 0.6)
			(layers "B.Cu" "B.Mask" "B.Paste")
			(roundrect_rratio 0.25)
			(net 1 "GND")
			(pintype "passive")
		)
		(pad "2" smd roundrect
			(at 0.498 0 180)
			(size 0.6 0.6)
			(layers "B.Cu" "B.Mask" "B.Paste")
			(roundrect_rratio 0.25)
			(net 188 "+1V8")
			(pintype "passive")
		)
	)
)
